FILE_TYPE = CONNECTIVITY;
{Allegro Design Entry HDL 16.6-p007 (v16-6-112F) 10/10/2012}
"PAGE_NUMBER" = 140;
0"NC";
1"P3V3_STBY\g";
2"GND\g";
3"GND\g";
4"GND\g";
5"SPI_NIC_MISO";
6"SPI_NIC_MISO_R";
7"SPI_NIC_MOSI";
8"PU_NV_HOLD_N";
9"PU_NV_WP_N";
10"SPI_NIC_SCLK";
11"SPI_NIC_CS_N";
%"M25PE16"
"1","(-2350,2700)","0","mstr_memory","I1";
;
CDS_SEC"1"
BOM_COST"NT_GBE_BASE"
SEC_TYPE"SM"
SEC"1"
ROOM"NIC_SPRV"
CDS_LOCATION"U9E1"
PACK_TYPE"SM"
CDS_LIB"mstr_memory"
LOCATION"U9E1"
MATERIAL"IC"
PART_NUMBER"H77797-001";
"VSS"
$PN"4"4;
"W_N"
$PN"3"9;
"RESET_N"
$PN"7"8;
"VCC"
$PN"8"1;
"S_N"
$PN"1"11;
"C"
$PN"6"10;
"DQ0"
$PN"5"7;
"DQ1"
$PN"2"6;
%"RES"
"2","(-3200,3300)","0","mstr_discrete","I10";
;
CDS_SEC"1"
SEC_TYPE"0402"
BOM_COST"NT_GBE_BASE"
CDS_LOCATION"R1R9"
SEC"1"
ROOM"NIC_SPRV"
CDS_LIB"mstr_discrete"
LOCATION"R1R9"
PART_NUMBER"G21796-027"
VALUE"3.32K"
PACK_TYPE"0402"
MATERIAL"CHIP"
WATTAGE"1/16W"
TOLERANCE"1%";
"A"
$PN"1"1;
"B"
$PN"2"8;
%"RES"
"2","(-3550,3300)","0","mstr_discrete","I11";
;
CDS_SEC"1"
SEC"1"
BOM_COST"NT_GBE_BASE"
SEC_TYPE"0402"
ROOM"NIC_SPRV"
CDS_LOCATION"R1R3"
CDS_LIB"mstr_discrete"
PART_NUMBER"G21796-027"
LOCATION"R1R3"
VALUE"3.32K"
TOLERANCE"1%"
WATTAGE"1/16W"
MATERIAL"CHIP"
PACK_TYPE"0402";
"A"
$PN"1"1;
"B"
$PN"2"9;
%"RES"
"2","(-3950,3300)","0","mstr_discrete","I12";
;
CDS_SEC"1"
BOM_COST"NT_GBE_BASE"
SEC_TYPE"0402"
SEC"1"
ROOM"NIC_SPRV"
CDS_LOCATION"R1R7"
CDS_LIB"mstr_discrete"
PART_NUMBER"G21796-040"
LOCATION"R1R7"
VALUE"20.0K"
PACK_TYPE"0402"
MATERIAL"CHIP"
WATTAGE"1/16W"
TOLERANCE"1%";
"A"
$PN"1"1;
"B"
$PN"2"7;
%"P3V3_STBY"
"1","(-3950,3625)","0","mstr_symbols","I13";
;
CDS_LIB"mstr_symbols"
SIZE"1B"
VOLTAGE"3.3V"
BODY_TYPE"PLUMBING"
HDL_POWER"P3V3_STBY";
"G\NAC"1;
%"RES"
"2","(-3825,2350)","0","mstr_discrete","I14";
;
CDS_SEC"1"
SEC"1"
SEC_TYPE"0402"
BOM_COST"NT_GBE_BASE"
ROOM"NIC_SPRV"
CDS_LOCATION"R1R6"
CDS_LIB"mstr_discrete"
PART_NUMBER"G21796-027"
LOCATION"R1R6"
VALUE"3.32K"
WATTAGE"1/16W"
TOLERANCE"1%"
MATERIAL"EMPTY"
PACK_TYPE"0402";
"A"
$PN"1"7;
"B"
$PN"2"2;
%"GND"
"1","(-3825,2075)","0","mstr_symbols","I16";
;
HDL_POWER"GND"
CDS_LIB"mstr_symbols"
SIZE"1B"
VOLTAGE"0.0V"
BODY_TYPE"PLUMBING";
"A\NAC"2;
%"RES"
"1","(-1400,2750)","0","mstr_discrete","I17";
;
CDS_SEC"1"
PACK_TYPE"0402"
ROOM"NIC_SPRV"
SEC"1"
BOM_COST"NT_GBE_BASE"
SEC_TYPE"0402"
CDS_LOCATION"R9E6"
CDS_LIB"mstr_discrete"
MATERIAL"CHIP"
PART_NUMBER"G21796-074"
LOCATION"R9E6"
TOLERANCE"1%"
VALUE"33.2"
WATTAGE"1/16W";
"B"
$PN"2"5;
"A"
$PN"1"6;
%"CAP_A"
"1","(-2475,3375)","0","dev_discrete","I3";
;
BOM_COST"NT_GBE_BASE"
SEC_TYPE"0402V"
SEC"1"
CDS_SEC"1"
CDS_LOCATION"C1R25"
ROOM"NIC_SPRV"
CDS_LIB"dev_discrete"
LOCATION"C1R25"
PART_NUMBER"A36096-030"
VALUE"0.1UF"
PACK_TYPE"0402V"
VOLTAGE"16V"
TOLERANCE"10%"
MATERIAL"X7R";
"B"
$PN"2"3;
"A"
$PN"1"1;
%"GND"
"1","(-2475,3100)","0","mstr_symbols","I4";
;
HDL_POWER"GND"
CDS_LIB"mstr_symbols"
SIZE"1B"
VOLTAGE"0.0V"
BODY_TYPE"PLUMBING";
"A\NAC"3;
%"GND"
"1","(-1900,2175)","0","mstr_symbols","I9";
;
HDL_POWER"GND"
BODY_TYPE"PLUMBING"
CDS_LIB"mstr_symbols"
SIZE"1B"
VOLTAGE"0.0V";
"A\NAC"4;
END.
